# T6G (Grand Teton) — schematic netlist excerpt (pin names and nets, part order shuffled) for the footprints in the layout excerpt that follows; sources: Cadence DE-HDL packaged netlist, KiCad conversion of 04192023_DAF0TMB3IC0_F0TG_MB_C_brd_V02_OCP.brd

C1794  Q_CAP_DIFFBUS  DIFF BUS_0.22UF 6.3V 20% X6S  pkg C0201  page 65 : \1\ = P5E_CPU0_G3_TX_C_DN<8> ; \2\ = P5E_CPU0_G3_TX_DN<8>
PR158  Q_RES  1.5 1% EMPTY  pkg 0402LF  page 203 : A = SW_PVDDCR_CPU1_P0_SW5_RC ; B = GND
PC570_5  Q_CAP  0.1UF 25V 10% X7R  pkg 0402  page 196 : A = SW_P12V_AUX_PVDDCR_CPU0_P0_FLT ; B = GND

(kicad_pcb
	(version 20260206)
	(generator "pcbnew")
	(generator_version "10.0")
	(general
		(thickness 1.6)
		(legacy_teardrops no)
	)
	(paper "A4")
	(title_block
		(title "04192023_DAF0TMB3IC0_F0TG_MB_C_brd_V02_OCP.brd")
		(comment 1 "Grand Teton / footprints 3344-3346 of 8354")
	)
	(layers
		(0 "F.Cu" signal "TOP")
		(4 "In1.Cu" signal "GND")
		(6 "In2.Cu" signal "IN1")
		(8 "In3.Cu" signal "GND1")
		(10 "In4.Cu" signal "IN2")
		(12 "In5.Cu" signal "GND2")
		(14 "In6.Cu" signal "IN3")
		(16 "In7.Cu" signal "GND3")
		(18 "In8.Cu" signal "VCC")
		(20 "In9.Cu" signal "VCC1")
		(22 "In10.Cu" signal "GND4")
		(24 "In11.Cu" signal "IN4")
		(26 "In12.Cu" signal "GND5")
		(28 "In13.Cu" signal "IN5")
		(30 "In14.Cu" signal "GND6")
		(32 "In15.Cu" signal "IN6")
		(34 "In16.Cu" signal "GND7")
		(2 "B.Cu" signal "BOTTOM")
		(9 "F.Adhes" user "F.Adhesive")
		(11 "B.Adhes" user "B.Adhesive")
		(13 "F.Paste" user "Package Geometry/Pastemask Top")
		(15 "B.Paste" user "Package Geometry/Pastemask Bottom")
		(5 "F.SilkS" user "Ref Des/Silkscreen Top")
		(7 "B.SilkS" user "Ref Des/Silkscreen Bottom")
		(1 "F.Mask" user "Board Geometry/Soldermask Top")
		(3 "B.Mask" user "Board Geometry/Soldermask Bottom")
		(17 "Dwgs.User" user "User.Drawings")
		(19 "Cmts.User" user "User.Comments")
		(21 "Eco1.User" user "User.Eco1")
		(23 "Eco2.User" user "User.Eco2")
		(25 "Edge.Cuts" user "Board Geometry/Outline")
		(27 "Margin" user)
		(31 "F.CrtYd" user "Package Geometry/Place Bound Top")
		(29 "B.CrtYd" user "Package Geometry/Place Bound Bottom")
		(35 "F.Fab" user "Ref Des/Assembly Top")
		(33 "B.Fab" user "Ref Des/Assembly Bottom")
	)
	(footprint ""
		(layer "F.Cu")
		(at 339.713062 -333.290164 90)
		(property "Reference" "PR158"
			(at 0 0 90)
			(layer "F.SilkS")
			(hide yes)
			(effects
				(font
					(size 1.27 1.27)
				)
			)
		)
		(property "Value" ""
			(at 0 0 90)
			(layer "F.Fab")
			(effects
				(font
					(size 1.27 1.27)
				)
			)
		)
		(duplicate_pad_numbers_are_jumpers no)
		(fp_line
			(start 0.7874 -0.4064)
			(end 0.7874 0.4064)
			(stroke
				(width 0.1524)
				(type default)
			)
			(layer "F.SilkS")
		)
		(fp_line
			(start -0.7874 -0.4064)
			(end 0.7874 -0.4064)
			(stroke
				(width 0.1524)
				(type default)
			)
			(layer "F.SilkS")
		)
		(fp_line
			(start 0.7874 0.4064)
			(end -0.7874 0.4064)
			(stroke
				(width 0.1524)
				(type default)
			)
			(layer "F.SilkS")
		)
		(fp_line
			(start -0.7874 0.4064)
			(end -0.7874 -0.4064)
			(stroke
				(width 0.1524)
				(type default)
			)
			(layer "F.SilkS")
		)
		(fp_line
			(start -0.12065 -0.305054)
			(end -0.12065 -0.2794)
			(stroke
				(width 0.1)
				(type default)
			)
			(layer "F.Fab")
		)
		(fp_line
			(start -0.67945 -0.305054)
			(end -0.12065 -0.305054)
			(stroke
				(width 0.1)
				(type default)
			)
			(layer "F.Fab")
		)
		(fp_line
			(start 0.67945 -0.3048)
			(end 0.67945 0.3048)
			(stroke
				(width 0.1)
				(type default)
			)
			(layer "F.Fab")
		)
		(fp_line
			(start 0.12065 -0.3048)
			(end 0.67945 -0.3048)
			(stroke
				(width 0.1)
				(type default)
			)
			(layer "F.Fab")
		)
		(fp_line
			(start 0.12065 -0.2794)
			(end 0.12065 -0.3048)
			(stroke
				(width 0.1)
				(type default)
			)
			(layer "F.Fab")
		)
		(fp_line
			(start -0.12065 -0.2794)
			(end 0.12065 -0.2794)
			(stroke
				(width 0.1)
				(type default)
			)
			(layer "F.Fab")
		)
		(fp_line
			(start 0.120396 0.2794)
			(end -0.12065 0.2794)
			(stroke
				(width 0.1)
				(type default)
			)
			(layer "F.Fab")
		)
		(fp_line
			(start -0.12065 0.2794)
			(end -0.12065 0.3048)
			(stroke
				(width 0.1)
				(type default)
			)
			(layer "F.Fab")
		)
		(fp_line
			(start 0.67945 0.3048)
			(end 0.120396 0.3048)
			(stroke
				(width 0.1)
				(type default)
			)
			(layer "F.Fab")
		)
		(fp_line
			(start 0.120396 0.3048)
			(end 0.120396 0.2794)
			(stroke
				(width 0.1)
				(type default)
			)
			(layer "F.Fab")
		)
		(fp_line
			(start -0.12065 0.3048)
			(end -0.67945 0.3048)
			(stroke
				(width 0.1)
				(type default)
			)
			(layer "F.Fab")
		)
		(fp_line
			(start -0.67945 0.3048)
			(end -0.67945 -0.305054)
			(stroke
				(width 0.1)
				(type default)
			)
			(layer "F.Fab")
		)
		(pad "1" smd circle
			(at -0.40005 0 90)
			(size 0 0)
			(layers "F.Cu" "F.Mask" "F.Paste")
			(net "SW_PVDDCR_CPU1_P0_SW5_RC")
		)
		(pad "2" smd circle
			(at 0.40005 0 90)
			(size 0 0)
			(layers "F.Cu" "F.Mask" "F.Paste")
			(net "GND")
		)
	)
	(footprint ""
		(layer "F.Cu")
		(at 409.565348 -17.624298 90)
		(property "Reference" "C1794"
			(at 0 0 90)
			(layer "F.SilkS")
			(hide yes)
			(effects
				(font
					(size 1.27 1.27)
				)
			)
		)
		(property "Value" ""
			(at 0 0 90)
			(layer "F.Fab")
			(effects
				(font
					(size 1.27 1.27)
				)
			)
		)
		(duplicate_pad_numbers_are_jumpers no)
		(fp_line
			(start 0.299974 -0.150114)
			(end 0.299974 0.150114)
			(stroke
				(width 0.1)
				(type default)
			)
			(layer "F.Fab")
		)
		(fp_line
			(start -0.299974 -0.150114)
			(end 0.299974 -0.150114)
			(stroke
				(width 0.1)
				(type default)
			)
			(layer "F.Fab")
		)
		(fp_line
			(start 0.299974 0.150114)
			(end -0.299974 0.150114)
			(stroke
				(width 0.1)
				(type default)
			)
			(layer "F.Fab")
		)
		(fp_line
			(start -0.299974 0.150114)
			(end -0.299974 -0.150114)
			(stroke
				(width 0.1)
				(type default)
			)
			(layer "F.Fab")
		)
		(pad "1" smd rect
			(at -0.2667 0 90)
			(size 0.3048 0.381)
			(layers "F.Cu" "F.Mask" "F.Paste")
			(net "P5E_CPU0_G3_TX_C_DN<8>")
		)
		(pad "2" smd rect
			(at 0.2667 0 90)
			(size 0.3048 0.381)
			(layers "F.Cu" "F.Mask" "F.Paste")
			(net "P5E_CPU0_G3_TX_DN<8>")
		)
	)
	(footprint ""
		(layer "F.Cu")
		(at 355.157278 -163.26231)
		(property "Reference" "PC570_5"
			(at 0 0 0)
			(layer "F.SilkS")
			(hide yes)
			(effects
				(font
					(size 1.27 1.27)
				)
			)
		)
		(property "Value" ""
			(at 0 0 0)
			(layer "F.Fab")
			(effects
				(font
					(size 1.27 1.27)
				)
			)
		)
		(duplicate_pad_numbers_are_jumpers no)
		(fp_line
			(start -0.7874 -0.4064)
			(end 0.7874 -0.4064)
			(stroke
				(width 0.1524)
				(type default)
			)
			(layer "F.SilkS")
		)
		(fp_line
			(start -0.7874 0.4064)
			(end -0.7874 -0.4064)
			(stroke
				(width 0.1524)
				(type default)
			)
			(layer "F.SilkS")
		)
		(fp_line
			(start 0.7874 -0.4064)
			(end 0.7874 0.4064)
			(stroke
				(width 0.1524)
				(type default)
			)
			(layer "F.SilkS")
		)
		(fp_line
			(start 0.7874 0.4064)
			(end -0.7874 0.4064)
			(stroke
				(width 0.1524)
				(type default)
			)
			(layer "F.SilkS")
		)
		(fp_line
			(start -0.67945 -0.305054)
			(end -0.12065 -0.305054)
			(stroke
				(width 0.1)
				(type default)
			)
			(layer "F.Fab")
		)
		(fp_line
			(start -0.67945 0.3048)
			(end -0.67945 -0.305054)
			(stroke
				(width 0.1)
				(type default)
			)
			(layer "F.Fab")
		)
		(fp_line
			(start -0.12065 -0.305054)
			(end -0.12065 -0.2794)
			(stroke
				(width 0.1)
				(type default)
			)
			(layer "F.Fab")
		)
		(fp_line
			(start -0.12065 -0.2794)
			(end 0.12065 -0.2794)
			(stroke
				(width 0.1)
				(type default)
			)
			(layer "F.Fab")
		)
		(fp_line
			(start -0.12065 0.2794)
			(end -0.12065 0.3048)
			(stroke
				(width 0.1)
				(type default)
			)
			(layer "F.Fab")
		)
		(fp_line
			(start -0.12065 0.3048)
			(end -0.67945 0.3048)
			(stroke
				(width 0.1)
				(type default)
			)
			(layer "F.Fab")
		)
		(fp_line
			(start 0.120396 0.2794)
			(end -0.12065 0.2794)
			(stroke
				(width 0.1)
				(type default)
			)
			(layer "F.Fab")
		)
		(fp_line
			(start 0.120396 0.3048)
			(end 0.120396 0.2794)
			(stroke
				(width 0.1)
				(type default)
			)
			(layer "F.Fab")
		)
		(fp_line
			(start 0.12065 -0.3048)
			(end 0.67945 -0.3048)
			(stroke
				(width 0.1)
				(type default)
			)
			(layer "F.Fab")
		)
		(fp_line
			(start 0.12065 -0.2794)
			(end 0.12065 -0.3048)
			(stroke
				(width 0.1)
				(type default)
			)
			(layer "F.Fab")
		)
		(fp_line
			(start 0.67945 -0.3048)
			(end 0.67945 0.3048)
			(stroke
				(width 0.1)
				(type default)
			)
			(layer "F.Fab")
		)
		(fp_line
			(start 0.67945 0.3048)
			(end 0.120396 0.3048)
			(stroke
				(width 0.1)
				(type default)
			)
			(layer "F.Fab")
		)
		(pad "1" smd circle
			(at -0.40005 0)
			(size 0 0)
			(layers "F.Cu" "F.Mask" "F.Paste")
			(net "SW_P12V_AUX_PVDDCR_CPU0_P0_FLT")
		)
		(pad "2" smd circle
			(at 0.40005 0)
			(size 0 0)
			(layers "F.Cu" "F.Mask" "F.Paste")
			(net "GND")
		)
	)
)
